(kicad_pcb
	(version 20241229)
	(generator "pcbnew")
	(generator_version "9.0")
	(general
		(thickness 1.599998)
		(legacy_teardrops no)
	)
	(paper "A4")
	(title_block
		(title "Artix - Datacenter Secure Control Module (DC-SCM)")
		(date "2024-11-06")
		(rev "1.1.3")
		(comment 9 "footprints 99-102 of 544")
	)
	(layers
		(0 "F.Cu" signal)
		(4 "In1.Cu" signal)
		(6 "In2.Cu" signal)
		(8 "In3.Cu" signal)
		(10 "In4.Cu" signal)
		(12 "In5.Cu" signal)
		(14 "In6.Cu" signal)
		(2 "B.Cu" signal)
		(9 "F.Adhes" user "F.Adhesive")
		(11 "B.Adhes" user "B.Adhesive")
		(13 "F.Paste" user)
		(15 "B.Paste" user)
		(5 "F.SilkS" user "F.Silkscreen")
		(7 "B.SilkS" user "B.Silkscreen")
		(1 "F.Mask" user)
		(3 "B.Mask" user)
		(17 "Dwgs.User" user "User.Drawings")
		(19 "Cmts.User" user "User.Comments")
		(21 "Eco1.User" user "User.Eco1")
		(23 "Eco2.User" user "User.Eco2")
		(25 "Edge.Cuts" user)
		(27 "Margin" user)
		(31 "F.CrtYd" user "F.Courtyard")
		(29 "B.CrtYd" user "B.Courtyard")
		(35 "F.Fab" user)
		(33 "B.Fab" user)
	)
	(footprint "antmicro-footprints:R_0402_1005Metric"
		(layer "F.Cu")
		(at 128.575 132.475)
		(descr "Resistor SMD 0402")
		(tags "resistor SMD 0402")
		(property "Reference" "R11"
			(at 0.725 0.425 0)
			(layer "F.SilkS")
			(effects
				(font
					(size 0.7 0.7)
					(thickness 0.15)
				)
				(justify left bottom)
			)
		)
		(property "Value" "R_0R_0402"
			(at 0 1.4 0)
			(layer "F.Fab")
			(effects
				(font
					(size 0.7 0.7)
					(thickness 0.15)
				)
				(justify left bottom)
			)
		)
		(property "Datasheet" "https://industrial.panasonic.com/cdbs/www-data/pdf/RDA0000/AOA0000C301.pdf"
			(at 0 0 0)
			(layer "F.Fab")
			(hide yes)
			(effects
				(font
					(size 1.27 1.27)
					(thickness 0.15)
				)
			)
		)
		(property "Description" "SMD Chip Resistor, Jumper, 0 ohm, 100 mW, 0402 [1005 Metric], Thick Film, General Purpose"
			(at 0 0 0)
			(layer "F.Fab")
			(hide yes)
			(effects
				(font
					(size 1.27 1.27)
					(thickness 0.15)
				)
			)
		)
		(property "Author" "Antmicro"
			(at 0 0 0)
			(layer "F.Fab")
			(hide yes)
			(effects
				(font
					(size 1 1)
					(thickness 0.15)
				)
			)
		)
		(property "Current" "1A"
			(at 0 0 0)
			(layer "F.Fab")
			(hide yes)
			(effects
				(font
					(size 1 1)
					(thickness 0.15)
				)
			)
		)
		(property "License" "Apache-2.0"
			(at 0 0 0)
			(layer "F.Fab")
			(hide yes)
			(effects
				(font
					(size 1 1)
					(thickness 0.15)
				)
			)
		)
		(property "MPN" "ERJ2GE0R00X"
			(at 0 0 0)
			(layer "F.Fab")
			(hide yes)
			(effects
				(font
					(size 1 1)
					(thickness 0.15)
				)
			)
		)
		(property "Manufacturer" "Panasonic"
			(at 0 0 0)
			(layer "F.Fab")
			(hide yes)
			(effects
				(font
					(size 1 1)
					(thickness 0.15)
				)
			)
		)
		(property "Tolerance" "~"
			(at 0 0 0)
			(layer "F.Fab")
			(hide yes)
			(effects
				(font
					(size 1 1)
					(thickness 0.15)
				)
			)
		)
		(property "Val" "0R"
			(at 0 0 0)
			(layer "F.Fab")
			(hide yes)
			(effects
				(font
					(size 1 1)
					(thickness 0.15)
				)
			)
		)
		(sheetname "/Interfaces/")
		(sheetfile "interfaces.kicad_sch")
		(attr smd)
		(fp_rect
			(start -0.925 -0.47)
			(end 0.925 0.47)
			(stroke
				(width 0.05)
				(type default)
			)
			(fill no)
			(layer "F.CrtYd")
		)
		(fp_rect
			(start -0.5 -0.25)
			(end 0.5 0.25)
			(stroke
				(width 0.15)
				(type solid)
			)
			(fill no)
			(layer "F.Fab")
		)
		(pad "1" smd roundrect
			(at -0.48 0)
			(size 0.59 0.64)
			(layers "F.Cu" "F.Mask" "F.Paste")
			(roundrect_rratio 0.25)
			(net 310 "Net-(U18-REG_EN)")
			(pintype "passive")
		)
		(pad "2" smd roundrect
			(at 0.48 0)
			(size 0.59 0.64)
			(layers "F.Cu" "F.Mask" "F.Paste")
			(roundrect_rratio 0.25)
			(net 2 "VCC3V3")
			(pintype "passive")
		)
	)
	(footprint "antmicro-footprints:R_0402_1005Metric"
		(layer "F.Cu")
		(at 105.074 154.675 -90)
		(descr "Resistor SMD 0402")
		(tags "resistor SMD 0402")
		(property "Reference" "R13"
			(at 1.225 8.874 90)
			(layer "F.SilkS")
			(effects
				(font
					(size 0.7 0.7)
					(thickness 0.15)
				)
				(justify right bottom)
			)
		)
		(property "Value" "R_4k7_0402"
			(at 0 1.4 90)
			(layer "F.Fab")
			(effects
				(font
					(size 0.7 0.7)
					(thickness 0.15)
				)
				(justify right bottom)
			)
		)
		(property "Datasheet" "https://www.bourns.com/docs/product-datasheets/cr.pdf"
			(at 0 0 270)
			(layer "F.Fab")
			(hide yes)
			(effects
				(font
					(size 1.27 1.27)
					(thickness 0.15)
				)
			)
		)
		(property "Description" "SMD Chip Resistor, 4.7 kohm, ± 1%, 62.5 mW, 0402 [1005 Metric], Thick Film, General Purpose"
			(at 0 0 270)
			(layer "F.Fab")
			(hide yes)
			(effects
				(font
					(size 1.27 1.27)
					(thickness 0.15)
				)
			)
		)
		(property "Author" "Antmicro"
			(at -49.601 259.749 0)
			(layer "F.Fab")
			(hide yes)
			(effects
				(font
					(size 1 1)
					(thickness 0.15)
				)
			)
		)
		(property "License" "Apache-2.0"
			(at -49.601 259.749 0)
			(layer "F.Fab")
			(hide yes)
			(effects
				(font
					(size 1 1)
					(thickness 0.15)
				)
			)
		)
		(property "MPN" "CR0402-FX-4701GLF"
			(at -49.601 259.749 0)
			(layer "F.Fab")
			(hide yes)
			(effects
				(font
					(size 1 1)
					(thickness 0.15)
				)
			)
		)
		(property "Manufacturer" "Bourns"
			(at -49.601 259.749 0)
			(layer "F.Fab")
			(hide yes)
			(effects
				(font
					(size 1 1)
					(thickness 0.15)
				)
			)
		)
		(property "Tolerance" "1%"
			(at -49.601 259.749 0)
			(layer "F.Fab")
			(hide yes)
			(effects
				(font
					(size 1 1)
					(thickness 0.15)
				)
			)
		)
		(property "Val" "4k7"
			(at -49.601 259.749 0)
			(layer "F.Fab")
			(hide yes)
			(effects
				(font
					(size 1 1)
					(thickness 0.15)
				)
			)
		)
		(sheetname "/DDR3/")
		(sheetfile "ddr3.kicad_sch")
		(attr smd)
		(fp_rect
			(start -0.925 -0.47)
			(end 0.925 0.47)
			(stroke
				(width 0.05)
				(type default)
			)
			(fill no)
			(layer "F.CrtYd")
		)
		(fp_rect
			(start -0.5 -0.25)
			(end 0.5 0.25)
			(stroke
				(width 0.15)
				(type solid)
			)
			(fill no)
			(layer "F.Fab")
		)
		(pad "1" smd roundrect
			(at -0.48 0 270)
			(size 0.59 0.64)
			(layers "F.Cu" "F.Mask" "F.Paste")
			(roundrect_rratio 0.25)
			(net 191 "DDR3_RESET")
			(pintype "passive")
		)
		(pad "2" smd roundrect
			(at 0.48 0 270)
			(size 0.59 0.64)
			(layers "F.Cu" "F.Mask" "F.Paste")
			(roundrect_rratio 0.25)
			(net 1 "GND")
			(pintype "passive")
		)
	)
	(footprint "antmicro-footprints:R_0402_1005Metric"
		(layer "F.Cu")
		(at 129.775 112.175 90)
		(descr "Resistor SMD 0402")
		(tags "resistor SMD 0402")
		(property "Reference" "R6"
			(at 0.775 0.425 90)
			(layer "F.SilkS")
			(effects
				(font
					(size 0.7 0.7)
					(thickness 0.15)
				)
				(justify left bottom)
			)
		)
		(property "Value" "R_1k_0402"
			(at 0 1.4 90)
			(layer "F.Fab")
			(effects
				(font
					(size 0.7 0.7)
					(thickness 0.15)
				)
				(justify left bottom)
			)
		)
		(property "Datasheet" "https://www.bourns.com/docs/product-datasheets/cr.pdf"
			(at 0 0 90)
			(layer "F.Fab")
			(hide yes)
			(effects
				(font
					(size 1.27 1.27)
					(thickness 0.15)
				)
			)
		)
		(property "Description" "SMD Chip Resistor, 1 kohm, ± 1%, 63 mW, 0402 [1005 Metric], Thick Film, General Purpose"
			(at 0 0 90)
			(layer "F.Fab")
			(hide yes)
			(effects
				(font
					(size 1.27 1.27)
					(thickness 0.15)
				)
			)
		)
		(property "Author" "Antmicro"
			(at 241.95 -17.6 0)
			(layer "F.Fab")
			(hide yes)
			(effects
				(font
					(size 1 1)
					(thickness 0.15)
				)
			)
		)
		(property "License" "Apache-2.0"
			(at 241.95 -17.6 0)
			(layer "F.Fab")
			(hide yes)
			(effects
				(font
					(size 1 1)
					(thickness 0.15)
				)
			)
		)
		(property "MPN" "CR0402-FX-1001GLF"
			(at 241.95 -17.6 0)
			(layer "F.Fab")
			(hide yes)
			(effects
				(font
					(size 1 1)
					(thickness 0.15)
				)
			)
		)
		(property "Manufacturer" "Bourns"
			(at 241.95 -17.6 0)
			(layer "F.Fab")
			(hide yes)
			(effects
				(font
					(size 1 1)
					(thickness 0.15)
				)
			)
		)
		(property "Tolerance" "1%"
			(at 241.95 -17.6 0)
			(layer "F.Fab")
			(hide yes)
			(effects
				(font
					(size 1 1)
					(thickness 0.15)
				)
			)
		)
		(property "Val" "1k"
			(at 241.95 -17.6 0)
			(layer "F.Fab")
			(hide yes)
			(effects
				(font
					(size 1 1)
					(thickness 0.15)
				)
			)
		)
		(sheetname "/Interfaces/")
		(sheetfile "interfaces.kicad_sch")
		(attr smd)
		(fp_rect
			(start -0.925 -0.47)
			(end 0.925 0.47)
			(stroke
				(width 0.05)
				(type default)
			)
			(fill no)
			(layer "F.CrtYd")
		)
		(fp_rect
			(start -0.5 -0.25)
			(end 0.5 0.25)
			(stroke
				(width 0.15)
				(type solid)
			)
			(fill no)
			(layer "F.Fab")
		)
		(pad "1" smd roundrect
			(at -0.48 0 90)
			(size 0.59 0.64)
			(layers "F.Cu" "F.Mask" "F.Paste")
			(roundrect_rratio 0.25)
			(net 4 "VCC5V0")
			(pintype "passive")
		)
		(pad "2" smd roundrect
			(at 0.48 0 90)
			(size 0.59 0.64)
			(layers "F.Cu" "F.Mask" "F.Paste")
			(roundrect_rratio 0.25)
			(net 302 "Net-(U17-VBUS)")
			(pintype "passive")
		)
	)
	(footprint "antmicro-footprints:R_0402_1005Metric"
		(layer "F.Cu")
		(at 129.075 128.175 90)
		(descr "Resistor SMD 0402")
		(tags "resistor SMD 0402")
		(property "Reference" "R8"
			(at 0.775 0.425 90)
			(layer "F.SilkS")
			(effects
				(font
					(size 0.7 0.7)
					(thickness 0.15)
				)
				(justify left bottom)
			)
		)
		(property "Value" "R_1k_0402"
			(at 0 1.4 90)
			(layer "F.Fab")
			(effects
				(font
					(size 0.7 0.7)
					(thickness 0.15)
				)
				(justify left bottom)
			)
		)
		(property "Datasheet" "https://www.bourns.com/docs/product-datasheets/cr.pdf"
			(at 0 0 90)
			(layer "F.Fab")
			(hide yes)
			(effects
				(font
					(size 1.27 1.27)
					(thickness 0.15)
				)
			)
		)
		(property "Description" "SMD Chip Resistor, 1 kohm, ± 1%, 63 mW, 0402 [1005 Metric], Thick Film, General Purpose"
			(at 0 0 90)
			(layer "F.Fab")
			(hide yes)
			(effects
				(font
					(size 1.27 1.27)
					(thickness 0.15)
				)
			)
		)
		(property "Author" "Antmicro"
			(at 257.25 -0.9 0)
			(layer "F.Fab")
			(hide yes)
			(effects
				(font
					(size 1 1)
					(thickness 0.15)
				)
			)
		)
		(property "License" "Apache-2.0"
			(at 257.25 -0.9 0)
			(layer "F.Fab")
			(hide yes)
			(effects
				(font
					(size 1 1)
					(thickness 0.15)
				)
			)
		)
		(property "MPN" "CR0402-FX-1001GLF"
			(at 257.25 -0.9 0)
			(layer "F.Fab")
			(hide yes)
			(effects
				(font
					(size 1 1)
					(thickness 0.15)
				)
			)
		)
		(property "Manufacturer" "Bourns"
			(at 257.25 -0.9 0)
			(layer "F.Fab")
			(hide yes)
			(effects
				(font
					(size 1 1)
					(thickness 0.15)
				)
			)
		)
		(property "Tolerance" "1%"
			(at 257.25 -0.9 0)
			(layer "F.Fab")
			(hide yes)
			(effects
				(font
					(size 1 1)
					(thickness 0.15)
				)
			)
		)
		(property "Val" "1k"
			(at 257.25 -0.9 0)
			(layer "F.Fab")
			(hide yes)
			(effects
				(font
					(size 1 1)
					(thickness 0.15)
				)
			)
		)
		(sheetname "/Interfaces/")
		(sheetfile "interfaces.kicad_sch")
		(attr smd)
		(fp_rect
			(start -0.925 -0.47)
			(end 0.925 0.47)
			(stroke
				(width 0.05)
				(type default)
			)
			(fill no)
			(layer "F.CrtYd")
		)
		(fp_rect
			(start -0.5 -0.25)
			(end 0.5 0.25)
			(stroke
				(width 0.15)
				(type solid)
			)
			(fill no)
			(layer "F.Fab")
		)
		(pad "1" smd roundrect
			(at -0.48 0 90)
			(size 0.59 0.64)
			(layers "F.Cu" "F.Mask" "F.Paste")
			(roundrect_rratio 0.25)
			(net 4 "VCC5V0")
			(pintype "passive")
		)
		(pad "2" smd roundrect
			(at 0.48 0 90)
			(size 0.59 0.64)
			(layers "F.Cu" "F.Mask" "F.Paste")
			(roundrect_rratio 0.25)
			(net 304 "Net-(U18-VBUS)")
			(pintype "passive")
		)
	)
)
